FILE_TYPE = CONNECTIVITY;
{Allegro Design Entry HDL 16.6-p007 (v16-6-112F) 10/10/2012}
"PAGE_NUMBER" = 195;
0"NC";
1"P12V_STBY\g";
2"GND\g";
3"P12V_PSU\g";
4"GND\g";
5"GND\g";
6"GND\g";
7"GND\g";
8"P12V_PSU\g";
9"P12V_PSU\g";
10"GND\g";
11"GND\g";
12"GND\g";
13"GND\g";
14"GND\g";
15"GND\g";
16"GND\g";
17"P12V_PSU\g";
18"GND\g";
19"P12V_PSU\g";
20"GND\g";
21"P12V_STBY\g";
22"P12V_STBY\g";
23"GND\g";
24"GND\g";
%"CAPP"
"1","(-7700,775)","0","mstr_discrete","I100";
;
CDS_SEC"1"
$SEC"1"
CDS_LOCATION"C3B6"
CDS_LIB"mstr_discrete"
PART_NUMBER"724613-112"
LOCATION"C3B6"
VALUE"68UF"
TOLERANCE"20%"
PACK_TYPE"3018"
VOLTAGE"16V"
MATERIAL"TANT";
"B"
$PN"2"23;
"A"
$PN"1"22;
%"CAPP"
"1","(-6175,775)","0","mstr_discrete","I101";
;
CDS_SEC"1"
$SEC"1"
CDS_LOCATION"C1R23"
CDS_LIB"mstr_discrete"
PART_NUMBER"724613-112"
LOCATION"C1R23"
VALUE"68UF"
TOLERANCE"20%"
PACK_TYPE"3018"
VOLTAGE"16V"
MATERIAL"TANT";
"B"
$PN"2"23;
"A"
$PN"1"22;
%"CAPP"
"1","(-4875,775)","0","mstr_discrete","I102";
;
CDS_SEC"1"
$SEC"1"
CDS_LOCATION"C4M6"
CDS_LIB"mstr_discrete"
PART_NUMBER"724613-112"
LOCATION"C4M6"
VALUE"68UF"
TOLERANCE"20%"
PACK_TYPE"3018"
VOLTAGE"16V"
MATERIAL"TANT";
"B"
$PN"2"23;
"A"
$PN"1"22;
%"CAPP"
"1","(-6550,775)","0","mstr_discrete","I103";
;
CDS_LOCATION"C1M5"
$SEC"1"
CDS_SEC"1"
CDS_LIB"mstr_discrete"
LOCATION"C1M5"
PART_NUMBER"724613-112"
VALUE"68UF"
PACK_TYPE"3018"
MATERIAL"TANT"
TOLERANCE"20%"
VOLTAGE"16V";
"B"
$PN"2"23;
"A"
$PN"1"22;
%"CAPP"
"1","(-5725,1950)","0","mstr_discrete","I104";
;
CDS_LOCATION"C3T13"
$SEC"1"
CDS_SEC"1"
CDS_LIB"mstr_discrete"
LOCATION"C3T13"
PART_NUMBER"724613-112"
VALUE"68UF"
TOLERANCE"20%"
PACK_TYPE"3018"
VOLTAGE"16V"
MATERIAL"TANT";
"B"
$PN"2"2;
"A"
$PN"1"1;
%"CAPP"
"1","(-4850,1950)","0","mstr_discrete","I105";
;
CDS_SEC"1"
$SEC"1"
CDS_LOCATION"C4M7"
CDS_LIB"mstr_discrete"
LOCATION"C4M7"
PART_NUMBER"724613-112"
PACK_TYPE"3018"
VOLTAGE"16V"
VALUE"68UF"
MATERIAL"TANT"
TOLERANCE"20%";
"B"
$PN"2"2;
"A"
$PN"1"1;
%"CAPP"
"1","(-5275,1925)","0","mstr_discrete","I106";
;
$SEC"1"
CDS_SEC"1"
CDS_LOCATION"C3T15"
CDS_LIB"mstr_discrete"
LOCATION"C3T15"
PART_NUMBER"724613-112"
VALUE"68UF"
PACK_TYPE"3018"
MATERIAL"TANT"
TOLERANCE"20%"
VOLTAGE"16V";
"B"
$PN"2"2;
"A"
$PN"1"1;
%"P12V_STBY"
"1","(-6375,2325)","0","mstr_symbols","I107";
;
CDS_LIB"mstr_symbols"
SIZE"1B"
VOLTAGE"12.0V"
BODY_TYPE"PLUMBING"
HDL_POWER"P12V_STBY";
"G\NAC"1;
%"CAPP"
"1","(-6150,1950)","0","mstr_discrete","I108";
;
CDS_LOCATION"C7M6"
$SEC"1"
CDS_SEC"1"
CDS_LIB"mstr_discrete"
LOCATION"C7M6"
PART_NUMBER"724613-112"
VALUE"68UF"
TOLERANCE"20%"
PACK_TYPE"3018"
VOLTAGE"16V"
MATERIAL"TANT";
"B"
$PN"2"2;
"A"
$PN"1"1;
%"CAPP"
"1","(-6525,1950)","0","mstr_discrete","I109";
;
CDS_SEC"1"
$SEC"1"
CDS_LOCATION"C6N5"
CDS_LIB"mstr_discrete"
LOCATION"C6N5"
PART_NUMBER"724613-112"
VALUE"68UF"
TOLERANCE"20%"
PACK_TYPE"3018"
VOLTAGE"16V"
MATERIAL"TANT";
"B"
$PN"2"2;
"A"
$PN"1"1;
%"GND"
"1","(-6375,1500)","0","mstr_symbols","I110";
;
HDL_POWER"GND"
CDS_LIB"mstr_symbols"
SIZE"1B"
VOLTAGE"0.0V"
BODY_TYPE"PLUMBING";
"A\NAC"2;
%"CAPP"
"1","(-6875,1950)","0","mstr_discrete","I111";
;
CDS_SEC"1"
$SEC"1"
CDS_LOCATION"C9T3"
CDS_LIB"mstr_discrete"
LOCATION"C9T3"
PART_NUMBER"724613-112"
VALUE"68UF"
TOLERANCE"20%"
PACK_TYPE"3018"
VOLTAGE"16V"
MATERIAL"TANT";
"B"
$PN"2"2;
"A"
$PN"1"1;
%"CAPP"
"1","(-7250,1950)","0","mstr_discrete","I112";
;
CDS_LOCATION"C4F4"
$SEC"1"
CDS_SEC"1"
CDS_LIB"mstr_discrete"
LOCATION"C4F4"
PART_NUMBER"724613-112"
VALUE"68UF"
TOLERANCE"20%"
PACK_TYPE"3018"
VOLTAGE"16V"
MATERIAL"TANT";
"B"
$PN"2"2;
"A"
$PN"1"1;
%"CAPP"
"1","(-7675,1950)","0","mstr_discrete","I113";
;
CDS_LOCATION"C3T3"
$SEC"1"
CDS_SEC"1"
CDS_LIB"mstr_discrete"
LOCATION"C3T3"
PART_NUMBER"724613-112"
MATERIAL"TANT"
PACK_TYPE"3018"
VOLTAGE"16V"
TOLERANCE"20%"
VALUE"68UF";
"B"
$PN"2"2;
"A"
$PN"1"1;
%"P12V_PSU"
"1","(-3700,2750)","0","mstr_symbols","I25";
;
HDL_POWER"P12V_PSU"
ROOM"P2V5_LAN_AUX_VR"
BODY_TYPE"PLUMBING"
CDS_LIB"mstr_symbols"
BOM_COST"NT_BASE_VRD"
VOLTAGE"12.0";
"G\NAC"3;
%"CONN3_G98259001"
"1","(-925,3725)","0","mstr_conn","I26";
;
CDS_LIB"mstr_conn"
CDS_LMAN_SYM_OUTLINE"-150,200,150,-200"
PACK_TYPE"PIP"
CDS_SEC"1"
$SEC"1"
CDS_LOCATION"RM1E1"
LOCATION"RM1E1"
PART_NUMBER"G98259-001"
MATERIAL"CONN";
"IO3"
$PN"3"4;
"IO2"
$PN"2"4;
"IO1"
$PN"1"4;
%"GND"
"1","(-475,3375)","0","mstr_symbols","I27";
;
HDL_POWER"GND"
CDS_LIB"mstr_symbols"
SIZE"1B"
BODY_TYPE"PLUMBING"
VOLTAGE"0.0V";
"A\NAC"4;
%"GND"
"1","(-3550,1900)","0","mstr_symbols","I28";
;
HDL_POWER"GND"
BODY_TYPE"PLUMBING"
CDS_LIB"mstr_symbols"
SIZE"1B"
VOLTAGE"0.0V";
"A\NAC"5;
%"CONN12_G98257001"
"1","(-3025,2250)","0","mstr_conn","I29";
;
CDS_SEC"1"
CDS_LIB"mstr_conn"
CDS_LMAN_SYM_OUTLINE"-200,250,200,-250"
PACK_TYPE"THMT"
SEC_TYPE"THMT"
SEC"1"
CDS_LOCATION"J1E1"
ROOM"HOT_SWAP"
LOCATION"J1E1"
MATERIAL"CONN"
PART_NUMBER"G98257-001";
"D3"
$PN"D3"7;
"D2"
$PN"D2"7;
"D1"
$PN"D1"7;
"C3"
$PN"C3"5;
"C2"
$PN"C2"5;
"C1"
$PN"C1"5;
"B3"
$PN"B3"3;
"B2"
$PN"B2"3;
"B1"
$PN"B1"3;
"A3"
$PN"A3"8;
"A2"
$PN"A2"8;
"A1"
$PN"A1"8;
%"GND"
"1","(-3700,3425)","0","mstr_symbols","I30";
;
HDL_POWER"GND"
CDS_LIB"mstr_symbols"
SIZE"1B"
BODY_TYPE"PLUMBING"
VOLTAGE"0.0V";
"A\NAC"6;
%"CAP"
"1","(-3700,3675)","0","mstr_discrete","I31";
;
CDS_SEC"1"
SEC_TYPE"0805"
SEC"1"
ROOM"HOT_SWAP"
CDS_LIB"mstr_discrete"
CDS_LOCATION"C9R5"
LOCATION"C9R5"
PART_NUMBER"C95333-007"
VALUE"10UF"
TOLERANCE"10%"
PACK_TYPE"0805"
VOLTAGE"16V"
MATERIAL"X6S";
"A"
$PN"1"9;
"B"
$PN"2"6;
%"CAP"
"1","(-3375,3675)","0","mstr_discrete","I32";
;
CDS_SEC"1"
SEC_TYPE"0805"
SEC"1"
CDS_LOCATION"C1E12"
ROOM"HOT_SWAP"
CDS_LIB"mstr_discrete"
PART_NUMBER"C95333-007"
TOLERANCE"10%"
VOLTAGE"16V"
VALUE"10UF"
LOCATION"C1E12"
MATERIAL"X6S"
PACK_TYPE"0805";
"A"
$PN"1"9;
"B"
$PN"2"6;
%"GND"
"1","(-2450,1900)","0","mstr_symbols","I33";
;
HDL_POWER"GND"
VOLTAGE"0.0V"
CDS_LIB"mstr_symbols"
SIZE"1B"
BODY_TYPE"PLUMBING";
"A\NAC"7;
%"P12V_PSU"
"1","(-2325,2750)","0","mstr_symbols","I34";
;
ROOM"P2V5_LAN_AUX_VR"
BODY_TYPE"PLUMBING"
BOM_COST"NT_BASE_VRD"
CDS_LIB"mstr_symbols"
VOLTAGE"12.0"
HDL_POWER"P12V_PSU";
"G\NAC"8;
%"CAP"
"1","(-3025,3675)","0","mstr_discrete","I35";
;
CDS_SEC"1"
SEC"1"
SEC_TYPE"0805"
ROOM"HOT_SWAP"
CDS_LOCATION"C1E15"
CDS_LIB"mstr_discrete"
LOCATION"C1E15"
VALUE"10UF"
TOLERANCE"10%"
VOLTAGE"16V"
MATERIAL"X6S"
PART_NUMBER"C95333-007"
PACK_TYPE"0805";
"A"
$PN"1"9;
"B"
$PN"2"6;
%"CAP_A"
"1","(-2675,3675)","0","dev_discrete","I36";
;
SEC_TYPE"0402V"
SEC"1"
BOM_COST"HOT_SWAP"
CDS_SEC"1"
CDS_LIB"dev_discrete"
ROOM"HOT_SWAP"
CDS_LOCATION"C9R12"
LOCATION"C9R12"
PART_NUMBER"A36096-030"
VALUE"0.1UF"
TOLERANCE"10%"
PACK_TYPE"0402V"
VOLTAGE"16V"
MATERIAL"X7R";
"B"
$PN"2"6;
"A"
$PN"1"9;
%"CAP_A"
"1","(-2300,3675)","0","dev_discrete","I37";
;
SEC"1"
SEC_TYPE"0402V"
CDS_SEC"1"
BOM_COST"HOT_SWAP"
ROOM"HOT_SWAP"
CDS_LOCATION"C9R6"
CDS_LIB"dev_discrete"
PART_NUMBER"A36096-030"
TOLERANCE"10%"
VALUE"0.1UF"
LOCATION"C9R6"
VOLTAGE"16V"
MATERIAL"X7R"
PACK_TYPE"0402V";
"B"
$PN"2"6;
"A"
$PN"1"9;
%"CAP_A"
"1","(-1950,3675)","0","dev_discrete","I38";
;
SEC"1"
SEC_TYPE"0402V"
CDS_SEC"1"
BOM_COST"HOT_SWAP"
ROOM"HOT_SWAP"
CDS_LOCATION"C1E17"
CDS_LIB"dev_discrete"
LOCATION"C1E17"
VALUE"0.1UF"
TOLERANCE"10%"
VOLTAGE"16V"
MATERIAL"X7R"
PACK_TYPE"0402V"
PART_NUMBER"A36096-030";
"B"
$PN"2"6;
"A"
$PN"1"9;
%"CAP_A"
"1","(-1625,3675)","0","dev_discrete","I39";
;
BOM_COST"HOT_SWAP"
SEC_TYPE"0402V"
SEC"1"
CDS_SEC"1"
ROOM"HOT_SWAP"
CDS_LOCATION"C1E16"
CDS_LIB"dev_discrete"
LOCATION"C1E16"
PART_NUMBER"A36096-030"
VALUE"0.1UF"
TOLERANCE"10%"
PACK_TYPE"0402V"
VOLTAGE"16V"
MATERIAL"X7R";
"B"
$PN"2"6;
"A"
$PN"1"9;
%"P12V_PSU"
"1","(-1625,4025)","0","mstr_symbols","I40";
;
BOM_COST"NT_BASE_VRD"
ROOM"P2V5_LAN_AUX_VR"
HDL_POWER"P12V_PSU"
BODY_TYPE"PLUMBING"
CDS_LIB"mstr_symbols"
VOLTAGE"12.0";
"G\NAC"9;
%"GND"
"1","(-6900,4525)","0","mstr_symbols","I48";
;
HDL_POWER"GND"
SIZE"1B"
CDS_LIB"mstr_symbols"
BODY_TYPE"PLUMBING"
VOLTAGE"0.0V";
"A\NAC"10;
%"MTG_KEYHOLE"
"1","(-6475,4725)","0","mstr_misc","I49";
;
CDS_LIB"mstr_misc"
PACK_TYPE"TH"
CDS_SEC"1"
BOM_COST"TEST_MFG"
CDS_LOCATION"TH4G1"
ROOM"MOUNTING_HOLES"
$SEC"1"
MATERIAL"EMPTY"
LOCATION"TH4G1"
PART_NUMBER"NA";
"1"
$PN"1"10;
%"MTG_KEYHOLE"
"1","(-6425,4125)","0","mstr_misc","I52";
;
PACK_TYPE"TH"
BOM_COST"TEST_MFG"
CDS_SEC"1"
$SEC"1"
ROOM"MOUNTING_HOLES"
CDS_LIB"mstr_misc"
CDS_LOCATION"TH9G1"
MATERIAL"EMPTY"
LOCATION"TH9G1"
PART_NUMBER"NA";
"1"
$PN"1"11;
%"GND"
"1","(-6850,3925)","0","mstr_symbols","I53";
;
HDL_POWER"GND"
BODY_TYPE"PLUMBING"
SIZE"1B"
CDS_LIB"mstr_symbols"
VOLTAGE"0.0V";
"A\NAC"11;
%"MTG_KEYHOLE"
"1","(-4600,4725)","0","mstr_misc","I54";
;
CDS_LIB"mstr_misc"
PACK_TYPE"TH"
BOM_COST"TEST_MFG"
CDS_SEC"1"
$SEC"1"
CDS_LOCATION"TH9A1"
ROOM"MOUNTING_HOLES"
MATERIAL"EMPTY"
LOCATION"TH9A1"
PART_NUMBER"NA";
"1"
$PN"1"12;
%"GND"
"1","(-5025,4525)","0","mstr_symbols","I55";
;
HDL_POWER"GND"
VOLTAGE"0.0V"
SIZE"1B"
CDS_LIB"mstr_symbols"
BODY_TYPE"PLUMBING";
"A\NAC"12;
%"MTG_KEYHOLE"
"1","(-5525,4725)","0","mstr_misc","I56";
;
CDS_LIB"mstr_misc"
ROOM"MOUNTING_HOLES"
CDS_LOCATION"TH1A1"
$SEC"1"
CDS_SEC"1"
BOM_COST"TEST_MFG"
PACK_TYPE"TH"
MATERIAL"EMPTY"
LOCATION"TH1A1"
PART_NUMBER"NA";
"1"
$PN"1"13;
%"GND"
"1","(-5950,4525)","0","mstr_symbols","I57";
;
HDL_POWER"GND"
SIZE"1B"
VOLTAGE"0.0V"
CDS_LIB"mstr_symbols"
BODY_TYPE"PLUMBING";
"A\NAC"13;
%"MTG_KEYHOLE"
"1","(-7350,4125)","0","mstr_misc","I62";
;
CDS_LIB"mstr_misc"
PACK_TYPE"TH"
BOM_COST"TEST_MFG"
CDS_SEC"1"
$SEC"1"
CDS_LOCATION"TH4A1"
ROOM"MOUNTING_HOLES"
MATERIAL"EMPTY"
LOCATION"TH4A1"
PART_NUMBER"NA";
"1"
$PN"1"14;
%"GND"
"1","(-7775,3925)","0","mstr_symbols","I63";
;
HDL_POWER"GND"
VOLTAGE"0.0V"
CDS_LIB"mstr_symbols"
SIZE"1B"
BODY_TYPE"PLUMBING";
"A\NAC"14;
%"GND"
"1","(-5950,3950)","0","mstr_symbols","I64";
;
HDL_POWER"GND"
BODY_TYPE"PLUMBING"
CDS_LIB"mstr_symbols"
SIZE"1B"
VOLTAGE"0.0V";
"A\NAC"15;
%"MTG_KEYHOLE"
"1","(-5525,4150)","0","mstr_misc","I65";
;
CDS_LIB"mstr_misc"
ROOM"MOUNTING_HOLES"
CDS_LOCATION"TH7A1"
$SEC"1"
CDS_SEC"1"
BOM_COST"TEST_MFG"
PACK_TYPE"TH"
MATERIAL"EMPTY"
LOCATION"TH7A1"
PART_NUMBER"NA";
"1"
$PN"1"15;
%"GND"
"1","(-5025,3950)","0","mstr_symbols","I66";
;
HDL_POWER"GND"
VOLTAGE"0.0V"
SIZE"1B"
CDS_LIB"mstr_symbols"
BODY_TYPE"PLUMBING";
"A\NAC"16;
%"MTG_KEYHOLE"
"1","(-4600,4150)","0","mstr_misc","I67";
;
CDS_LIB"mstr_misc"
PACK_TYPE"TH"
BOM_COST"TEST_MFG"
CDS_SEC"1"
$SEC"1"
ROOM"MOUNTING_HOLES"
CDS_LOCATION"TH7G1"
LOCATION"TH7G1"
MATERIAL"EMPTY"
PART_NUMBER"NA";
"1"
$PN"1"16;
%"CAPTIVE_SCREW"
"1","(-7500,4725)","0","mstr_misc","I76";
;
CDS_LIB"mstr_misc"
PACK_TYPE"TH"
BOM_COST"TEST_MFG"
CDS_LOCATION"RM1G1"
ROOM"MOUNTING_HOLES"
MATERIAL"HDW"
PART_NUMBER"H57868-001"
LOCATION"RM1G1";
%"P12V_PSU"
"1","(-550,2775)","0","mstr_symbols","I77";
;
VOLTAGE"12.0"
BOM_COST"NT_BASE_VRD"
CDS_LIB"mstr_symbols"
BODY_TYPE"PLUMBING"
ROOM"P2V5_LAN_AUX_VR"
HDL_POWER"P12V_PSU";
"G\NAC"17;
%"CONN12_G98257001"
"1","(-1250,2275)","0","mstr_conn","I78";
;
CDS_SEC"1"
SEC_TYPE"THMT"
PACK_TYPE"THMT"
SEC"1"
CDS_LOCATION"J1D1"
ROOM"HOT_SWAP"
CDS_LMAN_SYM_OUTLINE"-200,250,200,-250"
CDS_LIB"mstr_conn"
LOCATION"J1D1"
MATERIAL"CONN"
PART_NUMBER"G98257-001";
"D3"
$PN"D3"18;
"D2"
$PN"D2"18;
"D1"
$PN"D1"18;
"C3"
$PN"C3"20;
"C2"
$PN"C2"20;
"C1"
$PN"C1"20;
"B3"
$PN"B3"19;
"B2"
$PN"B2"19;
"B1"
$PN"B1"19;
"A3"
$PN"A3"17;
"A2"
$PN"A2"17;
"A1"
$PN"A1"17;
%"GND"
"1","(-675,1925)","0","mstr_symbols","I79";
;
HDL_POWER"GND"
BODY_TYPE"PLUMBING"
CDS_LIB"mstr_symbols"
SIZE"1B"
VOLTAGE"0.0V";
"A\NAC"18;
%"P12V_PSU"
"1","(-1925,2775)","0","mstr_symbols","I80";
;
ROOM"P2V5_LAN_AUX_VR"
BODY_TYPE"PLUMBING"
BOM_COST"NT_BASE_VRD"
CDS_LIB"mstr_symbols"
VOLTAGE"12.0"
HDL_POWER"P12V_PSU";
"G\NAC"19;
%"GND"
"1","(-1775,1925)","0","mstr_symbols","I81";
;
HDL_POWER"GND"
SIZE"1B"
CDS_LIB"mstr_symbols"
VOLTAGE"0.0V"
BODY_TYPE"PLUMBING";
"A\NAC"20;
%"CAPP"
"1","(-7175,2950)","0","mstr_discrete","I82";
;
$SEC"1"
CDS_SEC"1"
CDS_LOCATION"C4F6"
CDS_LIB"mstr_discrete"
LOCATION"C4F6"
PART_NUMBER"A93539-036"
VALUE"470UF"
TOLERANCE"20%"
PACK_TYPE"4040LF"
VOLTAGE"16V"
MATERIAL"ALUM";
"B"
$PN"2"24;
"A"
$PN"1"21;
%"CAPP"
"1","(-6675,2950)","0","mstr_discrete","I83";
;
$SEC"1"
CDS_SEC"1"
CDS_LOCATION"C4B13"
CDS_LIB"mstr_discrete"
LOCATION"C4B13"
PART_NUMBER"A93539-036"
VALUE"470UF"
TOLERANCE"20%"
PACK_TYPE"4040LF"
VOLTAGE"16V"
MATERIAL"ALUM";
"B"
$PN"2"24;
"A"
$PN"1"21;
%"CAPP"
"1","(-6150,2925)","0","mstr_discrete","I84";
;
$SEC"1"
CDS_SEC"1"
CDS_LOCATION"C1B14"
CDS_LIB"mstr_discrete"
MATERIAL"ALUM"
PART_NUMBER"A93539-036"
LOCATION"C1B14"
VALUE"470UF"
TOLERANCE"20%"
PACK_TYPE"4040LF"
VOLTAGE"16V";
"B"
$PN"2"24;
"A"
$PN"1"21;
%"CAPP"
"1","(-5650,2900)","0","mstr_discrete","I85";
;
CDS_SEC"1"
$SEC"1"
CDS_LOCATION"C1F7"
CDS_LIB"mstr_discrete"
MATERIAL"ALUM"
VOLTAGE"16V"
PACK_TYPE"4040LF"
TOLERANCE"20%"
VALUE"470UF"
PART_NUMBER"A93539-036"
LOCATION"C1F7";
"B"
$PN"2"24;
"A"
$PN"1"21;
%"P12V_STBY"
"1","(-6250,3375)","0","mstr_symbols","I92";
;
VOLTAGE"12.0V"
CDS_LIB"mstr_symbols"
SIZE"1B"
BODY_TYPE"PLUMBING"
HDL_POWER"P12V_STBY";
"G\NAC"21;
%"P12V_STBY"
"1","(-6400,1150)","0","mstr_symbols","I93";
;
SIZE"1B"
CDS_LIB"mstr_symbols"
VOLTAGE"12.0V"
BODY_TYPE"PLUMBING"
HDL_POWER"P12V_STBY";
"G\NAC"22;
%"GND"
"1","(-6400,325)","0","mstr_symbols","I94";
;
SIZE"1B"
HDL_POWER"GND"
CDS_LIB"mstr_symbols"
BODY_TYPE"PLUMBING"
VOLTAGE"0.0V";
"A\NAC"23;
%"GND"
"1","(-6375,2550)","0","mstr_symbols","I95";
;
HDL_POWER"GND"
CDS_LIB"mstr_symbols"
SIZE"1B"
VOLTAGE"0.0V"
BODY_TYPE"PLUMBING";
"A\NAC"24;
%"CAPP"
"1","(-7275,775)","0","mstr_discrete","I96";
;
CDS_LOCATION"C4F5"
$SEC"1"
CDS_SEC"1"
CDS_LIB"mstr_discrete"
LOCATION"C4F5"
PART_NUMBER"724613-112"
VALUE"68UF"
TOLERANCE"20%"
PACK_TYPE"3018"
VOLTAGE"16V"
MATERIAL"TANT";
"B"
$PN"2"23;
"A"
$PN"1"22;
%"CAPP"
"1","(-6900,775)","0","mstr_discrete","I97";
;
CDS_LOCATION"C4B14"
$SEC"1"
CDS_SEC"1"
CDS_LIB"mstr_discrete"
PART_NUMBER"724613-112"
TOLERANCE"20%"
LOCATION"C4B14"
VALUE"68UF"
MATERIAL"TANT"
VOLTAGE"16V"
PACK_TYPE"3018";
"B"
$PN"2"23;
"A"
$PN"1"22;
%"CAPP"
"1","(-5300,750)","0","mstr_discrete","I98";
;
CDS_SEC"1"
$SEC"1"
CDS_LOCATION"C3T6"
CDS_LIB"mstr_discrete"
PART_NUMBER"724613-112"
LOCATION"C3T6"
VALUE"68UF"
TOLERANCE"20%"
PACK_TYPE"3018"
VOLTAGE"16V"
MATERIAL"TANT";
"B"
$PN"2"23;
"A"
$PN"1"22;
%"CAPP"
"1","(-5750,775)","0","mstr_discrete","I99";
;
CDS_LOCATION"C9M3"
$SEC"1"
CDS_SEC"1"
CDS_LIB"mstr_discrete"
LOCATION"C9M3"
PART_NUMBER"724613-112"
VALUE"68UF"
TOLERANCE"20%"
PACK_TYPE"3018"
VOLTAGE"16V"
MATERIAL"TANT";
"B"
$PN"2"23;
"A"
$PN"1"22;
END.
